# T6G (Grand Teton) — schematic netlist excerpt (pin names and nets, part order shuffled) for the footprints in the layout excerpt that follows; sources: Cadence DE-HDL packaged netlist, KiCad conversion of 04192023_DAF0TMB3IC0_F0TG_MB_C_brd_V02_OCP.brd

R2676  Q_RES  0 5% CHIP  pkg 0402LF  page 248 : A = SMB_BMC_SWB_EN ; B = SMB_BMC_SWB_EN_R2
R401  Q_RES  1K 1% CHIP  pkg 0402LF  page 27 : A = PVDD18_S5_P0 ; B = JTAG_CPU0_TCK

(kicad_pcb
	(version 20260206)
	(generator "pcbnew")
	(generator_version "10.0")
	(general
		(thickness 1.6)
		(legacy_teardrops no)
	)
	(paper "A4")
	(title_block
		(title "04192023_DAF0TMB3IC0_F0TG_MB_C_brd_V02_OCP.brd")
		(comment 1 "Grand Teton / footprints 6798-6799 of 8354")
	)
	(layers
		(0 "F.Cu" signal "TOP")
		(4 "In1.Cu" signal "GND")
		(6 "In2.Cu" signal "IN1")
		(8 "In3.Cu" signal "GND1")
		(10 "In4.Cu" signal "IN2")
		(12 "In5.Cu" signal "GND2")
		(14 "In6.Cu" signal "IN3")
		(16 "In7.Cu" signal "GND3")
		(18 "In8.Cu" signal "VCC")
		(20 "In9.Cu" signal "VCC1")
		(22 "In10.Cu" signal "GND4")
		(24 "In11.Cu" signal "IN4")
		(26 "In12.Cu" signal "GND5")
		(28 "In13.Cu" signal "IN5")
		(30 "In14.Cu" signal "GND6")
		(32 "In15.Cu" signal "IN6")
		(34 "In16.Cu" signal "GND7")
		(2 "B.Cu" signal "BOTTOM")
		(9 "F.Adhes" user "F.Adhesive")
		(11 "B.Adhes" user "B.Adhesive")
		(13 "F.Paste" user "Package Geometry/Pastemask Top")
		(15 "B.Paste" user "Package Geometry/Pastemask Bottom")
		(5 "F.SilkS" user "Ref Des/Silkscreen Top")
		(7 "B.SilkS" user "Ref Des/Silkscreen Bottom")
		(1 "F.Mask" user "Board Geometry/Soldermask Top")
		(3 "B.Mask" user "Board Geometry/Soldermask Bottom")
		(17 "Dwgs.User" user "User.Drawings")
		(19 "Cmts.User" user "User.Comments")
		(21 "Eco1.User" user "User.Eco1")
		(23 "Eco2.User" user "User.Eco2")
		(25 "Edge.Cuts" user "Board Geometry/Outline")
		(27 "Margin" user)
		(31 "F.CrtYd" user "Package Geometry/Place Bound Top")
		(29 "B.CrtYd" user "Package Geometry/Place Bound Bottom")
		(35 "F.Fab" user "Ref Des/Assembly Top")
		(33 "B.Fab" user "Ref Des/Assembly Bottom")
	)
	(footprint ""
		(layer "B.Cu")
		(at 287.149286 -427.37151)
		(property "Reference" "R2676"
			(at 0 0 0)
			(layer "B.SilkS")
			(hide yes)
			(effects
				(font
					(size 1.27 1.27)
				)
				(justify mirror)
			)
		)
		(property "Value" ""
			(at 0 0 0)
			(layer "B.Fab")
			(effects
				(font
					(size 1.27 1.27)
				)
				(justify mirror)
			)
		)
		(duplicate_pad_numbers_are_jumpers no)
		(fp_line
			(start -0.7874 -0.4064)
			(end -0.7874 0.4064)
			(stroke
				(width 0.1524)
				(type default)
			)
			(layer "B.SilkS")
		)
		(fp_line
			(start -0.7874 0.4064)
			(end 0.7874 0.4064)
			(stroke
				(width 0.1524)
				(type default)
			)
			(layer "B.SilkS")
		)
		(fp_line
			(start 0.7874 -0.4064)
			(end -0.7874 -0.4064)
			(stroke
				(width 0.1524)
				(type default)
			)
			(layer "B.SilkS")
		)
		(fp_line
			(start 0.7874 0.4064)
			(end 0.7874 -0.4064)
			(stroke
				(width 0.1524)
				(type default)
			)
			(layer "B.SilkS")
		)
		(fp_line
			(start -0.67945 -0.3048)
			(end -0.67945 0.3048)
			(stroke
				(width 0.1)
				(type default)
			)
			(layer "B.Fab")
		)
		(fp_line
			(start -0.67945 0.3048)
			(end -0.120396 0.3048)
			(stroke
				(width 0.1)
				(type default)
			)
			(layer "B.Fab")
		)
		(fp_line
			(start -0.12065 -0.3048)
			(end -0.67945 -0.3048)
			(stroke
				(width 0.1)
				(type default)
			)
			(layer "B.Fab")
		)
		(fp_line
			(start -0.12065 -0.2794)
			(end -0.12065 -0.3048)
			(stroke
				(width 0.1)
				(type default)
			)
			(layer "B.Fab")
		)
		(fp_line
			(start -0.120396 0.2794)
			(end 0.12065 0.2794)
			(stroke
				(width 0.1)
				(type default)
			)
			(layer "B.Fab")
		)
		(fp_line
			(start -0.120396 0.3048)
			(end -0.120396 0.2794)
			(stroke
				(width 0.1)
				(type default)
			)
			(layer "B.Fab")
		)
		(fp_line
			(start 0.12065 -0.305054)
			(end 0.12065 -0.2794)
			(stroke
				(width 0.1)
				(type default)
			)
			(layer "B.Fab")
		)
		(fp_line
			(start 0.12065 -0.2794)
			(end -0.12065 -0.2794)
			(stroke
				(width 0.1)
				(type default)
			)
			(layer "B.Fab")
		)
		(fp_line
			(start 0.12065 0.2794)
			(end 0.12065 0.3048)
			(stroke
				(width 0.1)
				(type default)
			)
			(layer "B.Fab")
		)
		(fp_line
			(start 0.12065 0.3048)
			(end 0.67945 0.3048)
			(stroke
				(width 0.1)
				(type default)
			)
			(layer "B.Fab")
		)
		(fp_line
			(start 0.67945 -0.305054)
			(end 0.12065 -0.305054)
			(stroke
				(width 0.1)
				(type default)
			)
			(layer "B.Fab")
		)
		(fp_line
			(start 0.67945 0.3048)
			(end 0.67945 -0.305054)
			(stroke
				(width 0.1)
				(type default)
			)
			(layer "B.Fab")
		)
		(pad "1" smd circle
			(at 0.40005 0 180)
			(size 0 0)
			(layers "B.Cu" "B.Mask" "B.Paste")
			(net "SMB_BMC_SWB_EN")
		)
		(pad "2" smd circle
			(at -0.40005 0 180)
			(size 0 0)
			(layers "B.Cu" "B.Mask" "B.Paste")
			(net "SMB_BMC_SWB_EN_R2")
		)
	)
	(footprint ""
		(layer "B.Cu")
		(at 377.488958 -208.530952 -90)
		(property "Reference" "R401"
			(at 0 0 90)
			(layer "B.SilkS")
			(hide yes)
			(effects
				(font
					(size 1.27 1.27)
				)
				(justify mirror)
			)
		)
		(property "Value" ""
			(at 0 0 90)
			(layer "B.Fab")
			(effects
				(font
					(size 1.27 1.27)
				)
				(justify mirror)
			)
		)
		(duplicate_pad_numbers_are_jumpers no)
		(fp_line
			(start -0.7874 0.4064)
			(end 0.7874 0.4064)
			(stroke
				(width 0.1524)
				(type default)
			)
			(layer "B.SilkS")
		)
		(fp_line
			(start 0.7874 0.4064)
			(end 0.7874 -0.4064)
			(stroke
				(width 0.1524)
				(type default)
			)
			(layer "B.SilkS")
		)
		(fp_line
			(start -0.7874 -0.4064)
			(end -0.7874 0.4064)
			(stroke
				(width 0.1524)
				(type default)
			)
			(layer "B.SilkS")
		)
		(fp_line
			(start 0.7874 -0.4064)
			(end -0.7874 -0.4064)
			(stroke
				(width 0.1524)
				(type default)
			)
			(layer "B.SilkS")
		)
		(fp_line
			(start -0.67945 0.3048)
			(end -0.120396 0.3048)
			(stroke
				(width 0.1)
				(type default)
			)
			(layer "B.Fab")
		)
		(fp_line
			(start -0.120396 0.3048)
			(end -0.120396 0.2794)
			(stroke
				(width 0.1)
				(type default)
			)
			(layer "B.Fab")
		)
		(fp_line
			(start 0.12065 0.3048)
			(end 0.67945 0.3048)
			(stroke
				(width 0.1)
				(type default)
			)
			(layer "B.Fab")
		)
		(fp_line
			(start 0.67945 0.3048)
			(end 0.67945 -0.305054)
			(stroke
				(width 0.1)
				(type default)
			)
			(layer "B.Fab")
		)
		(fp_line
			(start -0.120396 0.2794)
			(end 0.12065 0.2794)
			(stroke
				(width 0.1)
				(type default)
			)
			(layer "B.Fab")
		)
		(fp_line
			(start 0.12065 0.2794)
			(end 0.12065 0.3048)
			(stroke
				(width 0.1)
				(type default)
			)
			(layer "B.Fab")
		)
		(fp_line
			(start -0.12065 -0.2794)
			(end -0.12065 -0.3048)
			(stroke
				(width 0.1)
				(type default)
			)
			(layer "B.Fab")
		)
		(fp_line
			(start 0.12065 -0.2794)
			(end -0.12065 -0.2794)
			(stroke
				(width 0.1)
				(type default)
			)
			(layer "B.Fab")
		)
		(fp_line
			(start -0.67945 -0.3048)
			(end -0.67945 0.3048)
			(stroke
				(width 0.1)
				(type default)
			)
			(layer "B.Fab")
		)
		(fp_line
			(start -0.12065 -0.3048)
			(end -0.67945 -0.3048)
			(stroke
				(width 0.1)
				(type default)
			)
			(layer "B.Fab")
		)
		(fp_line
			(start 0.12065 -0.305054)
			(end 0.12065 -0.2794)
			(stroke
				(width 0.1)
				(type default)
			)
			(layer "B.Fab")
		)
		(fp_line
			(start 0.67945 -0.305054)
			(end 0.12065 -0.305054)
			(stroke
				(width 0.1)
				(type default)
			)
			(layer "B.Fab")
		)
		(pad "1" smd circle
			(at 0.40005 0 90)
			(size 0 0)
			(layers "B.Cu" "B.Mask" "B.Paste")
			(net "PVDD18_S5_P0")
		)
		(pad "2" smd circle
			(at -0.40005 0 90)
			(size 0 0)
			(layers "B.Cu" "B.Mask" "B.Paste")
			(net "JTAG_CPU0_TCK")
		)
	)
)
